# S9S_MB_2U (Grand Teton) — schematic netlist excerpt (pin names and nets, part order shuffled) for the footprints in the layout excerpt that follows; sources: Cadence DE-HDL packaged netlist, KiCad conversion of 03242023_DA0F0TMBIJ0_F0T_Motherboard_J_brd_V01_OCP.brd

C1900  Q_CAP  0.01UF 50V 10% X7R  pkg C0402  page 217 : A = P3V3_AUX_FPGA_VCCIO2 ; B = GND
PC621_P1_1  Q_CAP  100NF 50V 10% X7R  pkg C0402  page 289 : A = PVCCFA_EHV_FIVRA_CPU1 ; B = GND

(kicad_pcb
	(version 20260206)
	(generator "pcbnew")
	(generator_version "10.0")
	(general
		(thickness 1.6)
		(legacy_teardrops no)
	)
	(paper "A4")
	(title_block
		(title "03242023_DA0F0TMBIJ0_F0T_Motherboard_J_brd_V01_OCP.brd")
		(comment 1 "Grand Teton / footprints 5915-5916 of 6105")
	)
	(layers
		(0 "F.Cu" signal "TOP")
		(4 "In1.Cu" signal "GND")
		(6 "In2.Cu" signal "IN1")
		(8 "In3.Cu" signal "GND1")
		(10 "In4.Cu" signal "IN2")
		(12 "In5.Cu" signal "GND2")
		(14 "In6.Cu" signal "IN3")
		(16 "In7.Cu" signal "GND3")
		(18 "In8.Cu" signal "VCC")
		(20 "In9.Cu" signal "VCC1")
		(22 "In10.Cu" signal "GND4")
		(24 "In11.Cu" signal "IN4")
		(26 "In12.Cu" signal "GND5")
		(28 "In13.Cu" signal "IN5")
		(30 "In14.Cu" signal "GND6")
		(32 "In15.Cu" signal "IN6")
		(34 "In16.Cu" signal "GND7")
		(2 "B.Cu" signal "BOTTOM")
		(9 "F.Adhes" user "F.Adhesive")
		(11 "B.Adhes" user "B.Adhesive")
		(13 "F.Paste" user "Package Geometry/Pastemask Top")
		(15 "B.Paste" user "Package Geometry/Pastemask Bottom")
		(5 "F.SilkS" user "Ref Des/Silkscreen Top")
		(7 "B.SilkS" user "Ref Des/Silkscreen Bottom")
		(1 "F.Mask" user "Board Geometry/Soldermask Top")
		(3 "B.Mask" user "Board Geometry/Soldermask Bottom")
		(17 "Dwgs.User" user "User.Drawings")
		(19 "Cmts.User" user "User.Comments")
		(21 "Eco1.User" user "User.Eco1")
		(23 "Eco2.User" user "User.Eco2")
		(25 "Edge.Cuts" user "Board Geometry/Outline")
		(27 "Margin" user)
		(31 "F.CrtYd" user "Package Geometry/Place Bound Top")
		(29 "B.CrtYd" user "Package Geometry/Place Bound Bottom")
		(35 "F.Fab" user "Ref Des/Assembly Top")
		(33 "B.Fab" user "Ref Des/Assembly Bottom")
	)
	(footprint ""
		(layer "B.Cu")
		(at 184.555638 -113.37544 -90)
		(property "Reference" "C1900"
			(at 0 0 90)
			(layer "B.SilkS")
			(hide yes)
			(effects
				(font
					(size 1.27 1.27)
				)
				(justify mirror)
			)
		)
		(property "Value" ""
			(at 0 0 90)
			(layer "B.Fab")
			(effects
				(font
					(size 1.27 1.27)
				)
				(justify mirror)
			)
		)
		(duplicate_pad_numbers_are_jumpers no)
		(fp_line
			(start -0.69215 0.2921)
			(end 0.69215 0.2921)
			(stroke
				(width 0.1524)
				(type default)
			)
			(layer "B.SilkS")
		)
		(fp_line
			(start 0.69215 0.2921)
			(end 0.69215 -0.2921)
			(stroke
				(width 0.1524)
				(type default)
			)
			(layer "B.SilkS")
		)
		(fp_line
			(start -0.69215 -0.2921)
			(end -0.69215 0.2921)
			(stroke
				(width 0.1524)
				(type default)
			)
			(layer "B.SilkS")
		)
		(fp_line
			(start 0.69215 -0.2921)
			(end -0.69215 -0.2921)
			(stroke
				(width 0.1524)
				(type default)
			)
			(layer "B.SilkS")
		)
		(fp_line
			(start -0.51435 0.2794)
			(end 0.51435 0.2794)
			(stroke
				(width 0.1)
				(type default)
			)
			(layer "B.Fab")
		)
		(fp_line
			(start 0.51435 0.2794)
			(end 0.51435 -0.2794)
			(stroke
				(width 0.1)
				(type default)
			)
			(layer "B.Fab")
		)
		(fp_line
			(start -0.51435 -0.2794)
			(end -0.51435 0.2794)
			(stroke
				(width 0.1)
				(type default)
			)
			(layer "B.Fab")
		)
		(fp_line
			(start 0.51435 -0.2794)
			(end -0.51435 -0.2794)
			(stroke
				(width 0.1)
				(type default)
			)
			(layer "B.Fab")
		)
		(pad "1" smd circle
			(at 0.40005 0 90)
			(size 0 0)
			(layers "B.Cu" "B.Mask" "B.Paste")
			(net "P3V3_AUX_FPGA_VCCIO2")
		)
		(pad "2" smd circle
			(at -0.40005 0 90)
			(size 0 0)
			(layers "B.Cu" "B.Mask" "B.Paste")
			(net "GND")
		)
		(zone
			(layer "B.Cu")
			(hatch none 0.5)
			(connect_pads
				(clearance 0)
			)
			(min_thickness 0.25)
			(keepout
				(tracks not_allowed)
				(vias allowed)
				(pads allowed)
				(copperpour not_allowed)
				(footprints allowed)
			)
			(placement
				(enabled no)
				(sheetname "")
			)
			(fill
				(thermal_gap 0.5)
				(thermal_bridge_width 0.5)
				(island_removal_mode 0)
			)
			(polygon
				(pts
					(xy 184.468008 -113.18494) (xy 184.409842 -113.27638) (xy 184.409842 -113.47577) (xy 184.468008 -113.56594)
					(xy 184.643268 -113.56594) (xy 184.701688 -113.47577) (xy 184.701688 -113.27638) (xy 184.643522 -113.18494)
				)
			)
		)
	)
	(footprint ""
		(layer "B.Cu")
		(at 177.00244 -344.79992 -90)
		(property "Reference" "PC621_P1_1"
			(at 0 0 90)
			(layer "B.SilkS")
			(hide yes)
			(effects
				(font
					(size 1.27 1.27)
				)
				(justify mirror)
			)
		)
		(property "Value" ""
			(at 0 0 90)
			(layer "B.Fab")
			(effects
				(font
					(size 1.27 1.27)
				)
				(justify mirror)
			)
		)
		(duplicate_pad_numbers_are_jumpers no)
		(fp_line
			(start -0.7874 0.4064)
			(end 0.7874 0.4064)
			(stroke
				(width 0.1524)
				(type default)
			)
			(layer "B.SilkS")
		)
		(fp_line
			(start 0.7874 0.4064)
			(end 0.7874 -0.4064)
			(stroke
				(width 0.1524)
				(type default)
			)
			(layer "B.SilkS")
		)
		(fp_line
			(start -0.7874 -0.4064)
			(end -0.7874 0.4064)
			(stroke
				(width 0.1524)
				(type default)
			)
			(layer "B.SilkS")
		)
		(fp_line
			(start 0.7874 -0.4064)
			(end -0.7874 -0.4064)
			(stroke
				(width 0.1524)
				(type default)
			)
			(layer "B.SilkS")
		)
		(fp_line
			(start -0.67945 0.3048)
			(end -0.120396 0.3048)
			(stroke
				(width 0.1)
				(type default)
			)
			(layer "B.Fab")
		)
		(fp_line
			(start -0.120396 0.3048)
			(end -0.120396 0.2794)
			(stroke
				(width 0.1)
				(type default)
			)
			(layer "B.Fab")
		)
		(fp_line
			(start 0.12065 0.3048)
			(end 0.67945 0.3048)
			(stroke
				(width 0.1)
				(type default)
			)
			(layer "B.Fab")
		)
		(fp_line
			(start 0.67945 0.3048)
			(end 0.67945 -0.305054)
			(stroke
				(width 0.1)
				(type default)
			)
			(layer "B.Fab")
		)
		(fp_line
			(start -0.120396 0.2794)
			(end 0.12065 0.2794)
			(stroke
				(width 0.1)
				(type default)
			)
			(layer "B.Fab")
		)
		(fp_line
			(start 0.12065 0.2794)
			(end 0.12065 0.3048)
			(stroke
				(width 0.1)
				(type default)
			)
			(layer "B.Fab")
		)
		(fp_line
			(start -0.12065 -0.2794)
			(end -0.12065 -0.3048)
			(stroke
				(width 0.1)
				(type default)
			)
			(layer "B.Fab")
		)
		(fp_line
			(start 0.12065 -0.2794)
			(end -0.12065 -0.2794)
			(stroke
				(width 0.1)
				(type default)
			)
			(layer "B.Fab")
		)
		(fp_line
			(start -0.67945 -0.3048)
			(end -0.67945 0.3048)
			(stroke
				(width 0.1)
				(type default)
			)
			(layer "B.Fab")
		)
		(fp_line
			(start -0.12065 -0.3048)
			(end -0.67945 -0.3048)
			(stroke
				(width 0.1)
				(type default)
			)
			(layer "B.Fab")
		)
		(fp_line
			(start 0.12065 -0.305054)
			(end 0.12065 -0.2794)
			(stroke
				(width 0.1)
				(type default)
			)
			(layer "B.Fab")
		)
		(fp_line
			(start 0.67945 -0.305054)
			(end 0.12065 -0.305054)
			(stroke
				(width 0.1)
				(type default)
			)
			(layer "B.Fab")
		)
		(pad "1" smd circle
			(at 0.40005 0 90)
			(size 0 0)
			(layers "B.Cu" "B.Mask" "B.Paste")
			(net "PVCCFA_EHV_FIVRA_CPU1")
		)
		(pad "2" smd circle
			(at -0.40005 0 90)
			(size 0 0)
			(layers "B.Cu" "B.Mask" "B.Paste")
			(net "GND")
		)
	)
)
